(kicad_pcb
	(version 20260206)
	(generator "pcbnew")
	(generator_version "10.0")
	(general
		(thickness 1.6)
		(legacy_teardrops no)
	)
	(paper "A4")
	(title_block
		(title "baseboard — 13948-1b.1110WZS1818.brd")
		(comment 1 "Honey Badger (Wiwynn) / footprints 1696-1702 of 2523")
	)
	(layers
		(0 "F.Cu" signal "TOP")
		(4 "In1.Cu" signal "L2GND")
		(6 "In2.Cu" signal "L3")
		(8 "In3.Cu" signal "L4VCC")
		(10 "In4.Cu" signal "L5VCC")
		(12 "In5.Cu" signal "L6")
		(14 "In6.Cu" signal "L7GND")
		(2 "B.Cu" signal "BOTTOM")
		(9 "F.Adhes" user "F.Adhesive")
		(11 "B.Adhes" user "B.Adhesive")
		(13 "F.Paste" user "Package Geometry/Pastemask Top")
		(15 "B.Paste" user "Package Geometry/Pastemask Bottom")
		(5 "F.SilkS" user "Ref Des/Silkscreen Top")
		(7 "B.SilkS" user "Ref Des/Silkscreen Bottom")
		(1 "F.Mask" user "Board Geometry/Soldermask Top")
		(3 "B.Mask" user "Board Geometry/Soldermask Bottom")
		(17 "Dwgs.User" user "User.Drawings")
		(19 "Cmts.User" user "User.Comments")
		(21 "Eco1.User" user "User.Eco1")
		(23 "Eco2.User" user "User.Eco2")
		(25 "Edge.Cuts" user "Board Geometry/Outline")
		(27 "Margin" user)
		(31 "F.CrtYd" user "Package Geometry/Place Bound Top")
		(29 "B.CrtYd" user "Package Geometry/Place Bound Bottom")
		(35 "F.Fab" user "Ref Des/Assembly Top")
		(33 "B.Fab" user "Ref Des/Assembly Bottom")
	)
	(footprint ""
		(layer "F.Cu")
		(at 306.07 -160.655)
		(property "Reference" "R806"
			(at 0 0 0)
			(layer "F.SilkS")
			(hide yes)
			(effects
				(font
					(size 1.27 1.27)
				)
			)
		)
		(property "Value" "0R2J-2-GP"
			(at 0.064008 -3.993896 0)
			(unlocked yes)
			(layer "F.Fab")
			(hide yes)
			(effects
				(font
					(size 1.016 1.016)
					(thickness 0.1524)
				)
			)
		)
		(property "Device Type" "R402H16"
			(at 0.064008 -5.517896 0)
			(unlocked yes)
			(layer "F.Fab")
			(hide yes)
			(effects
				(font
					(size 1.016 1.016)
					(thickness 0.1524)
				)
			)
		)
		(duplicate_pad_numbers_are_jumpers no)
		(fp_line
			(start -0.508 -0.9398)
			(end -0.508 0.9398)
			(stroke
				(width 0.1524)
				(type default)
			)
			(layer "F.SilkS")
		)
		(fp_line
			(start 0.508 -0.9398)
			(end -0.508 -0.9398)
			(stroke
				(width 0.1524)
				(type default)
			)
			(layer "F.SilkS")
		)
		(fp_rect
			(start -0.508 0.9398)
			(end 0.508 -0.9398)
			(stroke
				(width 0)
				(type default)
			)
			(fill no)
			(layer "F.CrtYd")
		)
		(fp_rect
			(start -0.508 0.9398)
			(end 0.508 -0.9398)
			(stroke
				(width 0)
				(type default)
			)
			(fill no)
			(layer "F.Fab")
		)
		(pad "1" smd custom
			(at 0 -0.4445)
			(size 0.1397 0.1397)
			(layers "F.Cu" "F.Mask" "F.Paste")
			(net "DP_BMC_CPU_RST_N_R")
			(options
				(clearance outline)
				(anchor circle)
			)
			(primitives
				(gr_poly
					(pts
						(arc
							(start -0.1778 -0.2794)
							(mid -0.249642 -0.249642)
							(end -0.2794 -0.1778)
						)
						(arc
							(start -0.2794 0.1778)
							(mid -0.249642 0.249642)
							(end -0.1778 0.2794)
						)
						(arc
							(start 0.1778 0.2794)
							(mid 0.249642 0.249642)
							(end 0.2794 0.1778)
						)
						(arc
							(start 0.2794 -0.1778)
							(mid 0.249642 -0.249642)
							(end 0.1778 -0.2794)
						)
					)
					(width 0)
					(fill yes)
				)
			)
		)
		(pad "2" smd custom
			(at 0 0.4445)
			(size 0.1397 0.1397)
			(layers "F.Cu" "F.Mask" "F.Paste")
			(net "DP_BMC_CPU_RST_N")
			(options
				(clearance outline)
				(anchor circle)
			)
			(primitives
				(gr_poly
					(pts
						(arc
							(start -0.1778 -0.2794)
							(mid -0.249642 -0.249642)
							(end -0.2794 -0.1778)
						)
						(arc
							(start -0.2794 0.1778)
							(mid -0.249642 0.249642)
							(end -0.1778 0.2794)
						)
						(arc
							(start 0.1778 0.2794)
							(mid 0.249642 0.249642)
							(end 0.2794 0.1778)
						)
						(arc
							(start 0.2794 -0.1778)
							(mid 0.249642 -0.249642)
							(end 0.1778 -0.2794)
						)
					)
					(width 0)
					(fill yes)
				)
			)
		)
	)
	(footprint ""
		(layer "F.Cu")
		(at 175.390048 -32.499808)
		(property "Reference" "R402"
			(at 0 0 0)
			(layer "F.SilkS")
			(hide yes)
			(effects
				(font
					(size 1.27 1.27)
				)
			)
		)
		(property "Value" "49D9R2F-GP"
			(at 0.064008 -3.993896 0)
			(unlocked yes)
			(layer "F.Fab")
			(hide yes)
			(effects
				(font
					(size 1.016 1.016)
					(thickness 0.1524)
				)
			)
		)
		(property "Device Type" "R402H16"
			(at 0.064008 -5.517896 0)
			(unlocked yes)
			(layer "F.Fab")
			(hide yes)
			(effects
				(font
					(size 1.016 1.016)
					(thickness 0.1524)
				)
			)
		)
		(duplicate_pad_numbers_are_jumpers no)
		(fp_line
			(start -0.508 -0.9398)
			(end -0.508 0.9398)
			(stroke
				(width 0.1524)
				(type default)
			)
			(layer "F.SilkS")
		)
		(fp_line
			(start 0.508 -0.9398)
			(end -0.508 -0.9398)
			(stroke
				(width 0.1524)
				(type default)
			)
			(layer "F.SilkS")
		)
		(fp_rect
			(start -0.508 0.9398)
			(end 0.508 -0.9398)
			(stroke
				(width 0)
				(type default)
			)
			(fill no)
			(layer "F.CrtYd")
		)
		(fp_rect
			(start -0.508 0.9398)
			(end 0.508 -0.9398)
			(stroke
				(width 0)
				(type default)
			)
			(fill no)
			(layer "F.Fab")
		)
		(pad "1" smd custom
			(at 0 -0.4445)
			(size 0.1397 0.1397)
			(layers "F.Cu" "F.Mask" "F.Paste")
			(net "MOD_IMC_FAB_D_COP")
			(options
				(clearance outline)
				(anchor circle)
			)
			(primitives
				(gr_poly
					(pts
						(arc
							(start -0.1778 -0.2794)
							(mid -0.249642 -0.249642)
							(end -0.2794 -0.1778)
						)
						(arc
							(start -0.2794 0.1778)
							(mid -0.249642 0.249642)
							(end -0.1778 0.2794)
						)
						(arc
							(start 0.1778 0.2794)
							(mid 0.249642 0.249642)
							(end 0.2794 0.1778)
						)
						(arc
							(start 0.2794 -0.1778)
							(mid 0.249642 -0.249642)
							(end 0.1778 -0.2794)
						)
					)
					(width 0)
					(fill yes)
				)
			)
		)
		(pad "2" smd custom
			(at 0 0.4445)
			(size 0.1397 0.1397)
			(layers "F.Cu" "F.Mask" "F.Paste")
			(net "BCM5221_RX_C_DN")
			(options
				(clearance outline)
				(anchor circle)
			)
			(primitives
				(gr_poly
					(pts
						(arc
							(start -0.1778 -0.2794)
							(mid -0.249642 -0.249642)
							(end -0.2794 -0.1778)
						)
						(arc
							(start -0.2794 0.1778)
							(mid -0.249642 0.249642)
							(end -0.1778 0.2794)
						)
						(arc
							(start 0.1778 0.2794)
							(mid 0.249642 0.249642)
							(end 0.2794 0.1778)
						)
						(arc
							(start 0.2794 -0.1778)
							(mid 0.249642 -0.249642)
							(end 0.1778 -0.2794)
						)
					)
					(width 0)
					(fill yes)
				)
			)
		)
	)
	(footprint ""
		(layer "F.Cu")
		(at 317.5 -108.585 -90)
		(property "Reference" "PR33"
			(at 0 0 270)
			(layer "F.SilkS")
			(hide yes)
			(effects
				(font
					(size 1.27 1.27)
				)
			)
		)
		(property "Value" "44K2R2F-1-GP"
			(at 0.064008 -3.993896 270)
			(unlocked yes)
			(layer "F.Fab")
			(hide yes)
			(effects
				(font
					(size 1.016 1.016)
					(thickness 0.1524)
				)
			)
		)
		(property "Device Type" "R402H16"
			(at 0.064008 -5.517896 270)
			(unlocked yes)
			(layer "F.Fab")
			(hide yes)
			(effects
				(font
					(size 1.016 1.016)
					(thickness 0.1524)
				)
			)
		)
		(duplicate_pad_numbers_are_jumpers no)
		(fp_line
			(start -0.508 -0.9398)
			(end -0.508 0.9398)
			(stroke
				(width 0.1524)
				(type default)
			)
			(layer "F.SilkS")
		)
		(fp_line
			(start 0.508 -0.9398)
			(end -0.508 -0.9398)
			(stroke
				(width 0.1524)
				(type default)
			)
			(layer "F.SilkS")
		)
		(fp_rect
			(start -0.508 0.9398)
			(end 0.508 -0.9398)
			(stroke
				(width 0)
				(type default)
			)
			(fill no)
			(layer "F.CrtYd")
		)
		(fp_rect
			(start -0.508 0.9398)
			(end 0.508 -0.9398)
			(stroke
				(width 0)
				(type default)
			)
			(fill no)
			(layer "F.Fab")
		)
		(pad "1" smd custom
			(at 0 -0.4445 270)
			(size 0.1397 0.1397)
			(layers "F.Cu" "F.Mask" "F.Paste")
			(net "P3V3_STBY_VFB")
			(options
				(clearance outline)
				(anchor circle)
			)
			(primitives
				(gr_poly
					(pts
						(arc
							(start -0.1778 -0.2794)
							(mid -0.249642 -0.249642)
							(end -0.2794 -0.1778)
						)
						(arc
							(start -0.2794 0.1778)
							(mid -0.249642 0.249642)
							(end -0.1778 0.2794)
						)
						(arc
							(start 0.1778 0.2794)
							(mid 0.249642 0.249642)
							(end 0.2794 0.1778)
						)
						(arc
							(start 0.2794 -0.1778)
							(mid 0.249642 -0.249642)
							(end 0.1778 -0.2794)
						)
					)
					(width 0)
					(fill yes)
				)
			)
		)
		(pad "2" smd custom
			(at 0 0.4445 270)
			(size 0.1397 0.1397)
			(layers "F.Cu" "F.Mask" "F.Paste")
			(net "P3V3_STBY_VFB_R")
			(options
				(clearance outline)
				(anchor circle)
			)
			(primitives
				(gr_poly
					(pts
						(arc
							(start -0.1778 -0.2794)
							(mid -0.249642 -0.249642)
							(end -0.2794 -0.1778)
						)
						(arc
							(start -0.2794 0.1778)
							(mid -0.249642 0.249642)
							(end -0.1778 0.2794)
						)
						(arc
							(start 0.1778 0.2794)
							(mid 0.249642 0.249642)
							(end 0.2794 0.1778)
						)
						(arc
							(start 0.2794 -0.1778)
							(mid 0.249642 -0.249642)
							(end 0.1778 -0.2794)
						)
					)
					(width 0)
					(fill yes)
				)
			)
		)
	)
	(footprint ""
		(layer "F.Cu")
		(at 324.104 -168.148)
		(property "Reference" "R275"
			(at 0 0 0)
			(layer "F.SilkS")
			(hide yes)
			(effects
				(font
					(size 1.27 1.27)
				)
			)
		)
		(property "Value" "0R2J-2-GP"
			(at 0.064008 -3.993896 0)
			(unlocked yes)
			(layer "F.Fab")
			(hide yes)
			(effects
				(font
					(size 1.016 1.016)
					(thickness 0.1524)
				)
			)
		)
		(property "Device Type" "R402H16"
			(at 0.064008 -5.517896 0)
			(unlocked yes)
			(layer "F.Fab")
			(hide yes)
			(effects
				(font
					(size 1.016 1.016)
					(thickness 0.1524)
				)
			)
		)
		(duplicate_pad_numbers_are_jumpers no)
		(fp_line
			(start -0.508 -0.9398)
			(end -0.508 0.9398)
			(stroke
				(width 0.1524)
				(type default)
			)
			(layer "F.SilkS")
		)
		(fp_line
			(start 0.508 -0.9398)
			(end -0.508 -0.9398)
			(stroke
				(width 0.1524)
				(type default)
			)
			(layer "F.SilkS")
		)
		(fp_rect
			(start -0.508 0.9398)
			(end 0.508 -0.9398)
			(stroke
				(width 0)
				(type default)
			)
			(fill no)
			(layer "F.CrtYd")
		)
		(fp_rect
			(start -0.508 0.9398)
			(end 0.508 -0.9398)
			(stroke
				(width 0)
				(type default)
			)
			(fill no)
			(layer "F.Fab")
		)
		(pad "1" smd custom
			(at 0 -0.4445)
			(size 0.1397 0.1397)
			(layers "F.Cu" "F.Mask" "F.Paste")
			(net "BMC_UART_SWITCH_1R")
			(options
				(clearance outline)
				(anchor circle)
			)
			(primitives
				(gr_poly
					(pts
						(arc
							(start -0.1778 -0.2794)
							(mid -0.249642 -0.249642)
							(end -0.2794 -0.1778)
						)
						(arc
							(start -0.2794 0.1778)
							(mid -0.249642 0.249642)
							(end -0.1778 0.2794)
						)
						(arc
							(start 0.1778 0.2794)
							(mid 0.249642 0.249642)
							(end 0.2794 0.1778)
						)
						(arc
							(start 0.2794 -0.1778)
							(mid 0.249642 -0.249642)
							(end 0.1778 -0.2794)
						)
					)
					(width 0)
					(fill yes)
				)
			)
		)
		(pad "2" smd custom
			(at 0 0.4445)
			(size 0.1397 0.1397)
			(layers "F.Cu" "F.Mask" "F.Paste")
			(net "BMC_UART_SWITCH_1")
			(options
				(clearance outline)
				(anchor circle)
			)
			(primitives
				(gr_poly
					(pts
						(arc
							(start -0.1778 -0.2794)
							(mid -0.249642 -0.249642)
							(end -0.2794 -0.1778)
						)
						(arc
							(start -0.2794 0.1778)
							(mid -0.249642 0.249642)
							(end -0.1778 0.2794)
						)
						(arc
							(start 0.1778 0.2794)
							(mid 0.249642 0.249642)
							(end 0.2794 0.1778)
						)
						(arc
							(start 0.2794 -0.1778)
							(mid 0.249642 -0.249642)
							(end 0.1778 -0.2794)
						)
					)
					(width 0)
					(fill yes)
				)
			)
		)
	)
	(footprint ""
		(layer "F.Cu")
		(at 38.9128 -168.5036)
		(property "Reference" "C371"
			(at 0 0 0)
			(layer "F.SilkS")
			(hide yes)
			(effects
				(font
					(size 1.27 1.27)
				)
			)
		)
		(property "Value" "SC1U6D3V3KX-2GP"
			(at 0 -2.8194 0)
			(unlocked yes)
			(layer "F.Fab")
			(hide yes)
			(effects
				(font
					(size 1.016 1.016)
					(thickness 0.1524)
				)
			)
		)
		(property "Device Type" "C603H36"
			(at 0 -4.3434 0)
			(unlocked yes)
			(layer "F.Fab")
			(hide yes)
			(effects
				(font
					(size 1.016 1.016)
					(thickness 0.1524)
				)
			)
		)
		(duplicate_pad_numbers_are_jumpers no)
		(fp_line
			(start 0.508 0)
			(end -0.508 0)
			(stroke
				(width 0.2032)
				(type default)
			)
			(layer "F.SilkS")
		)
		(fp_rect
			(start -0.5842 1.3335)
			(end 0.5842 -1.3335)
			(stroke
				(width 0)
				(type default)
			)
			(fill no)
			(layer "F.CrtYd")
		)
		(fp_rect
			(start -0.5842 1.3335)
			(end 0.5842 -1.3335)
			(stroke
				(width 0)
				(type default)
			)
			(fill no)
			(layer "F.Fab")
		)
		(pad "1" smd custom
			(at 0 -0.762)
			(size 0.2159 0.2159)
			(layers "F.Cu" "F.Mask" "F.Paste")
			(net "P3V3_STBY")
			(options
				(clearance outline)
				(anchor circle)
			)
			(primitives
				(gr_poly
					(pts
						(arc
							(start -0.3302 -0.4318)
							(mid -0.402042 -0.402042)
							(end -0.4318 -0.3302)
						)
						(arc
							(start -0.4318 0.3302)
							(mid -0.402042 0.402042)
							(end -0.3302 0.4318)
						)
						(arc
							(start 0.3302 0.4318)
							(mid 0.402042 0.402042)
							(end 0.4318 0.3302)
						)
						(arc
							(start 0.4318 -0.3302)
							(mid 0.402042 -0.402042)
							(end 0.3302 -0.4318)
						)
					)
					(width 0)
					(fill yes)
				)
			)
		)
		(pad "2" smd custom
			(at 0 0.762)
			(size 0.2159 0.2159)
			(layers "F.Cu" "F.Mask" "F.Paste")
			(net "GND")
			(options
				(clearance outline)
				(anchor circle)
			)
			(primitives
				(gr_poly
					(pts
						(arc
							(start -0.3302 -0.4318)
							(mid -0.402042 -0.402042)
							(end -0.4318 -0.3302)
						)
						(arc
							(start -0.4318 0.3302)
							(mid -0.402042 0.402042)
							(end -0.3302 0.4318)
						)
						(arc
							(start 0.3302 0.4318)
							(mid 0.402042 0.402042)
							(end 0.4318 0.3302)
						)
						(arc
							(start 0.4318 -0.3302)
							(mid 0.402042 -0.402042)
							(end 0.3302 -0.4318)
						)
					)
					(width 0)
					(fill yes)
				)
			)
		)
	)
	(footprint ""
		(layer "F.Cu")
		(at 96.247966 -69.342 180)
		(property "Reference" "SC970"
			(at 0 0 180)
			(layer "F.SilkS")
			(hide yes)
			(effects
				(font
					(size 1.27 1.27)
				)
			)
		)
		(property "Value" "SC1U10V2KX-4-GP"
			(at 1.1811 -2.7051 180)
			(unlocked yes)
			(layer "F.Fab")
			(hide yes)
			(effects
				(font
					(size 1.016 1.016)
					(thickness 0.1524)
				)
			)
		)
		(property "Device Type" "C402H22"
			(at 1.1811 -4.2291 180)
			(unlocked yes)
			(layer "F.Fab")
			(hide yes)
			(effects
				(font
					(size 1.016 1.016)
					(thickness 0.1524)
				)
			)
		)
		(duplicate_pad_numbers_are_jumpers no)
		(fp_rect
			(start -0.4318 0.9525)
			(end 0.4318 -0.9525)
			(stroke
				(width 0)
				(type default)
			)
			(fill no)
			(layer "F.CrtYd")
		)
		(fp_rect
			(start -0.4318 0.9525)
			(end 0.4318 -0.9525)
			(stroke
				(width 0)
				(type default)
			)
			(fill no)
			(layer "F.Fab")
		)
		(pad "1" smd custom
			(at 0 -0.4445 180)
			(size 0.1524 0.1524)
			(layers "F.Cu" "F.Mask" "F.Paste")
			(net "P1V8_C")
			(options
				(clearance outline)
				(anchor circle)
			)
			(primitives
				(gr_poly
					(pts
						(arc
							(start 0.3048 -0.2032)
							(mid 0.275042 -0.275042)
							(end 0.2032 -0.3048)
						)
						(arc
							(start -0.2032 -0.3048)
							(mid -0.275042 -0.275042)
							(end -0.3048 -0.2032)
						)
						(arc
							(start -0.3048 0.2032)
							(mid -0.275042 0.275042)
							(end -0.2032 0.3048)
						)
						(arc
							(start 0.2032 0.3048)
							(mid 0.275042 0.275042)
							(end 0.3048 0.2032)
						)
					)
					(width 0)
					(fill yes)
				)
			)
		)
		(pad "2" smd custom
			(at 0 0.4445 180)
			(size 0.1524 0.1524)
			(layers "F.Cu" "F.Mask" "F.Paste")
			(net "GND")
			(options
				(clearance outline)
				(anchor circle)
			)
			(primitives
				(gr_poly
					(pts
						(arc
							(start 0.3048 -0.2032)
							(mid 0.275042 -0.275042)
							(end 0.2032 -0.3048)
						)
						(arc
							(start -0.2032 -0.3048)
							(mid -0.275042 -0.275042)
							(end -0.3048 -0.2032)
						)
						(arc
							(start -0.3048 0.2032)
							(mid -0.275042 0.275042)
							(end -0.2032 0.3048)
						)
						(arc
							(start 0.2032 0.3048)
							(mid 0.275042 0.275042)
							(end 0.3048 0.2032)
						)
					)
					(width 0)
					(fill yes)
				)
			)
		)
	)
	(footprint ""
		(layer "F.Cu")
		(at 98.18497 -76.454)
		(property "Reference" "SR862"
			(at 0 0 0)
			(layer "F.SilkS")
			(hide yes)
			(effects
				(font
					(size 1.27 1.27)
				)
			)
		)
		(property "Value" "0R2J-2-GP"
			(at 0.064008 -3.993896 0)
			(unlocked yes)
			(layer "F.Fab")
			(hide yes)
			(effects
				(font
					(size 1.016 1.016)
					(thickness 0.1524)
				)
			)
		)
		(property "Device Type" "R402H16"
			(at 0.064008 -5.517896 0)
			(unlocked yes)
			(layer "F.Fab")
			(hide yes)
			(effects
				(font
					(size 1.016 1.016)
					(thickness 0.1524)
				)
			)
		)
		(duplicate_pad_numbers_are_jumpers no)
		(fp_line
			(start -0.508 -0.9398)
			(end -0.508 0.9398)
			(stroke
				(width 0.1524)
				(type default)
			)
			(layer "F.SilkS")
		)
		(fp_line
			(start 0.508 -0.9398)
			(end -0.508 -0.9398)
			(stroke
				(width 0.1524)
				(type default)
			)
			(layer "F.SilkS")
		)
		(fp_rect
			(start -0.508 0.9398)
			(end 0.508 -0.9398)
			(stroke
				(width 0)
				(type default)
			)
			(fill no)
			(layer "F.CrtYd")
		)
		(fp_rect
			(start -0.508 0.9398)
			(end 0.508 -0.9398)
			(stroke
				(width 0)
				(type default)
			)
			(fill no)
			(layer "F.Fab")
		)
		(pad "1" smd custom
			(at 0 -0.4445)
			(size 0.1397 0.1397)
			(layers "F.Cu" "F.Mask" "F.Paste")
			(net "JTAG_EXP_TCK")
			(options
				(clearance outline)
				(anchor circle)
			)
			(primitives
				(gr_poly
					(pts
						(arc
							(start -0.1778 -0.2794)
							(mid -0.249642 -0.249642)
							(end -0.2794 -0.1778)
						)
						(arc
							(start -0.2794 0.1778)
							(mid -0.249642 0.249642)
							(end -0.1778 0.2794)
						)
						(arc
							(start 0.1778 0.2794)
							(mid 0.249642 0.249642)
							(end 0.2794 0.1778)
						)
						(arc
							(start 0.2794 -0.1778)
							(mid 0.249642 -0.249642)
							(end 0.1778 -0.2794)
						)
					)
					(width 0)
					(fill yes)
				)
			)
		)
		(pad "2" smd custom
			(at 0 0.4445)
			(size 0.1397 0.1397)
			(layers "F.Cu" "F.Mask" "F.Paste")
			(net "JTAG_EXP_IOC_TCK")
			(options
				(clearance outline)
				(anchor circle)
			)
			(primitives
				(gr_poly
					(pts
						(arc
							(start -0.1778 -0.2794)
							(mid -0.249642 -0.249642)
							(end -0.2794 -0.1778)
						)
						(arc
							(start -0.2794 0.1778)
							(mid -0.249642 0.249642)
							(end -0.1778 0.2794)
						)
						(arc
							(start 0.1778 0.2794)
							(mid 0.249642 0.249642)
							(end 0.2794 0.1778)
						)
						(arc
							(start 0.2794 -0.1778)
							(mid 0.249642 -0.249642)
							(end 0.1778 -0.2794)
						)
					)
					(width 0)
					(fill yes)
				)
			)
		)
	)
)
